(kicad_pcb
	(version 20260206)
	(generator "pcbnew")
	(generator_version "10.0")
	(general
		(thickness 1.6)
		(legacy_teardrops no)
	)
	(paper "A4")
	(title_block
		(title "03242023_DA0F0TMBIJ0_F0T_Motherboard_J_brd_V01_OCP.brd")
		(comment 1 "Grand Teton / footprints 6038-6044 of 6105")
	)
	(layers
		(0 "F.Cu" signal "TOP")
		(4 "In1.Cu" signal "GND")
		(6 "In2.Cu" signal "IN1")
		(8 "In3.Cu" signal "GND1")
		(10 "In4.Cu" signal "IN2")
		(12 "In5.Cu" signal "GND2")
		(14 "In6.Cu" signal "IN3")
		(16 "In7.Cu" signal "GND3")
		(18 "In8.Cu" signal "VCC")
		(20 "In9.Cu" signal "VCC1")
		(22 "In10.Cu" signal "GND4")
		(24 "In11.Cu" signal "IN4")
		(26 "In12.Cu" signal "GND5")
		(28 "In13.Cu" signal "IN5")
		(30 "In14.Cu" signal "GND6")
		(32 "In15.Cu" signal "IN6")
		(34 "In16.Cu" signal "GND7")
		(2 "B.Cu" signal "BOTTOM")
		(9 "F.Adhes" user "F.Adhesive")
		(11 "B.Adhes" user "B.Adhesive")
		(13 "F.Paste" user "Package Geometry/Pastemask Top")
		(15 "B.Paste" user "Package Geometry/Pastemask Bottom")
		(5 "F.SilkS" user "Ref Des/Silkscreen Top")
		(7 "B.SilkS" user "Ref Des/Silkscreen Bottom")
		(1 "F.Mask" user "Board Geometry/Soldermask Top")
		(3 "B.Mask" user "Board Geometry/Soldermask Bottom")
		(17 "Dwgs.User" user "User.Drawings")
		(19 "Cmts.User" user "User.Comments")
		(21 "Eco1.User" user "User.Eco1")
		(23 "Eco2.User" user "User.Eco2")
		(25 "Edge.Cuts" user "Board Geometry/Outline")
		(27 "Margin" user)
		(31 "F.CrtYd" user "Package Geometry/Place Bound Top")
		(29 "B.CrtYd" user "Package Geometry/Place Bound Bottom")
		(35 "F.Fab" user "Ref Des/Assembly Top")
		(33 "B.Fab" user "Ref Des/Assembly Bottom")
	)
	(footprint ""
		(layer "B.Cu")
		(at 87.489284 -190.705232 -90)
		(property "Reference" "R65"
			(at 0 0 90)
			(layer "B.SilkS")
			(hide yes)
			(effects
				(font
					(size 1.27 1.27)
				)
				(justify mirror)
			)
		)
		(property "Value" ""
			(at 0 0 90)
			(layer "B.Fab")
			(effects
				(font
					(size 1.27 1.27)
				)
				(justify mirror)
			)
		)
		(duplicate_pad_numbers_are_jumpers no)
		(fp_line
			(start -0.7874 0.4064)
			(end 0.7874 0.4064)
			(stroke
				(width 0.1524)
				(type default)
			)
			(layer "B.SilkS")
		)
		(fp_line
			(start 0.7874 0.4064)
			(end 0.7874 -0.4064)
			(stroke
				(width 0.1524)
				(type default)
			)
			(layer "B.SilkS")
		)
		(fp_line
			(start -0.7874 -0.4064)
			(end -0.7874 0.4064)
			(stroke
				(width 0.1524)
				(type default)
			)
			(layer "B.SilkS")
		)
		(fp_line
			(start 0.7874 -0.4064)
			(end -0.7874 -0.4064)
			(stroke
				(width 0.1524)
				(type default)
			)
			(layer "B.SilkS")
		)
		(fp_line
			(start -0.67945 0.3048)
			(end -0.120396 0.3048)
			(stroke
				(width 0.1)
				(type default)
			)
			(layer "B.Fab")
		)
		(fp_line
			(start -0.120396 0.3048)
			(end -0.120396 0.2794)
			(stroke
				(width 0.1)
				(type default)
			)
			(layer "B.Fab")
		)
		(fp_line
			(start 0.12065 0.3048)
			(end 0.67945 0.3048)
			(stroke
				(width 0.1)
				(type default)
			)
			(layer "B.Fab")
		)
		(fp_line
			(start 0.67945 0.3048)
			(end 0.67945 -0.305054)
			(stroke
				(width 0.1)
				(type default)
			)
			(layer "B.Fab")
		)
		(fp_line
			(start -0.120396 0.2794)
			(end 0.12065 0.2794)
			(stroke
				(width 0.1)
				(type default)
			)
			(layer "B.Fab")
		)
		(fp_line
			(start 0.12065 0.2794)
			(end 0.12065 0.3048)
			(stroke
				(width 0.1)
				(type default)
			)
			(layer "B.Fab")
		)
		(fp_line
			(start -0.12065 -0.2794)
			(end -0.12065 -0.3048)
			(stroke
				(width 0.1)
				(type default)
			)
			(layer "B.Fab")
		)
		(fp_line
			(start 0.12065 -0.2794)
			(end -0.12065 -0.2794)
			(stroke
				(width 0.1)
				(type default)
			)
			(layer "B.Fab")
		)
		(fp_line
			(start -0.67945 -0.3048)
			(end -0.67945 0.3048)
			(stroke
				(width 0.1)
				(type default)
			)
			(layer "B.Fab")
		)
		(fp_line
			(start -0.12065 -0.3048)
			(end -0.67945 -0.3048)
			(stroke
				(width 0.1)
				(type default)
			)
			(layer "B.Fab")
		)
		(fp_line
			(start 0.12065 -0.305054)
			(end 0.12065 -0.2794)
			(stroke
				(width 0.1)
				(type default)
			)
			(layer "B.Fab")
		)
		(fp_line
			(start 0.67945 -0.305054)
			(end 0.12065 -0.305054)
			(stroke
				(width 0.1)
				(type default)
			)
			(layer "B.Fab")
		)
		(pad "1" smd circle
			(at 0.40005 0 90)
			(size 0 0)
			(layers "B.Cu" "B.Mask" "B.Paste")
			(net "JTAG_DBP_CPU_GTL_TCK")
		)
		(pad "2" smd circle
			(at -0.40005 0 90)
			(size 0 0)
			(layers "B.Cu" "B.Mask" "B.Paste")
			(net "JTAG_DBP_CPU1_GTL_R_TCK")
		)
	)
	(footprint ""
		(layer "B.Cu")
		(at 216.986358 -194.41795)
		(property "Reference" "U16"
			(at 2.2606 -2.352548 0)
			(unlocked yes)
			(layer "B.SilkS")
			(effects
				(font
					(size 0.7874 0.5842)
					(thickness 0.1524)
				)
				(justify left mirror)
			)
		)
		(property "Value" ""
			(at 0 0 0)
			(layer "B.Fab")
			(effects
				(font
					(size 1.27 1.27)
				)
				(justify mirror)
			)
		)
		(duplicate_pad_numbers_are_jumpers no)
		(fp_line
			(start -2.032 -1.549908)
			(end -2.032 1.549908)
			(stroke
				(width 0.1524)
				(type default)
			)
			(layer "B.SilkS")
		)
		(fp_line
			(start -2.032 1.549908)
			(end 2.032 1.549908)
			(stroke
				(width 0.1524)
				(type default)
			)
			(layer "B.SilkS")
		)
		(fp_line
			(start 2.032 -1.549908)
			(end -2.032 -1.549908)
			(stroke
				(width 0.1524)
				(type default)
			)
			(layer "B.SilkS")
		)
		(fp_line
			(start 2.032 1.549908)
			(end 2.032 -1.549908)
			(stroke
				(width 0.1524)
				(type default)
			)
			(layer "B.SilkS")
		)
		(fp_poly
			(pts
				(xy 2.9464 -1.2192) (xy 2.9464 -0.7112) (xy 2.1844 -0.9652)
			)
			(stroke
				(width 0)
				(type default)
			)
			(fill yes)
			(layer "B.SilkS")
		)
		(fp_line
			(start -0.849884 -1.549908)
			(end 0.849884 -1.549908)
			(stroke
				(width 0.1)
				(type default)
			)
			(layer "B.Fab")
		)
		(fp_line
			(start -0.849884 1.549908)
			(end -0.849884 -1.549908)
			(stroke
				(width 0.1)
				(type default)
			)
			(layer "B.Fab")
		)
		(fp_line
			(start 0.849884 -1.549908)
			(end 0.849884 1.549908)
			(stroke
				(width 0.1)
				(type default)
			)
			(layer "B.Fab")
		)
		(fp_line
			(start 0.849884 1.549908)
			(end -0.849884 1.549908)
			(stroke
				(width 0.1)
				(type default)
			)
			(layer "B.Fab")
		)
		(fp_poly
			(pts
				(xy 2.9464 -1.2192) (xy 2.9464 -0.7112) (xy 2.1844 -0.9652)
			)
			(stroke
				(width 0)
				(type default)
			)
			(fill yes)
			(layer "B.Fab")
		)
		(pad "1" smd rect
			(at 1.225042 -0.94996 270)
			(size 0.4572 1.3208)
			(layers "B.Cu" "B.Mask" "B.Paste")
			(net "JTAG_CPU0_MUX_GTL_TDO")
		)
		(pad "2" smd rect
			(at 1.225042 0 270)
			(size 0.4572 1.3208)
			(layers "B.Cu" "B.Mask" "B.Paste")
			(net "JTAG_MUX_CPU1_GTL_TDI")
		)
		(pad "3" smd rect
			(at 1.225042 0.94996 270)
			(size 0.4572 1.3208)
			(layers "B.Cu" "B.Mask" "B.Paste")
			(net "GND")
		)
		(pad "4" smd rect
			(at -1.225042 0.94996 270)
			(size 0.4572 1.3208)
			(layers "B.Cu" "B.Mask" "B.Paste")
			(net "FM_CPU_EN_R")
		)
		(pad "5" smd rect
			(at -1.225042 -0.94996 270)
			(size 0.4572 1.3208)
			(layers "B.Cu" "B.Mask" "B.Paste")
			(net "P3V3_AUX")
		)
	)
	(footprint ""
		(layer "B.Cu")
		(at 120.458484 -359.596436 -90)
		(property "Reference" "PJ66"
			(at -4.067302 -0.128016 0)
			(unlocked yes)
			(layer "B.SilkS")
			(effects
				(font
					(size 0.7874 0.5842)
					(thickness 0.1524)
				)
				(justify left mirror)
			)
		)
		(property "Value" ""
			(at 0 0 90)
			(layer "B.Fab")
			(effects
				(font
					(size 1.27 1.27)
				)
				(justify mirror)
			)
		)
		(duplicate_pad_numbers_are_jumpers no)
		(pad "1" smd circle
			(at 0.7493 0)
			(size 0 0)
			(layers "B.Cu" "B.Mask" "B.Paste")
			(net "SH_PVPP_HBM_CPU1_P")
		)
		(pad "2" smd rect
			(at -0.7493 0 180)
			(size 0.7112 0.8128)
			(layers "B.Cu" "B.Mask" "B.Paste")
			(net "PVPP_HBM_CPU1")
		)
		(zone
			(layer "B.Cu")
			(hatch none 0.5)
			(connect_pads
				(clearance 0)
			)
			(min_thickness 0.25)
			(keepout
				(tracks allowed)
				(vias not_allowed)
				(pads allowed)
				(copperpour not_allowed)
				(footprints allowed)
			)
			(placement
				(enabled no)
				(sheetname "")
			)
			(fill
				(thermal_gap 0.5)
				(thermal_bridge_width 0.5)
				(island_removal_mode 0)
			)
			(polygon
				(pts
					(xy 120.047258 -358.415336) (xy 120.864884 -358.415336) (xy 120.864884 -360.802936) (xy 120.047258 -360.802936)
				)
			)
		)
	)
	(footprint ""
		(layer "B.Cu")
		(at 211.632546 -321.554856 -90)
		(property "Reference" "C76"
			(at 0 0 90)
			(layer "B.SilkS")
			(hide yes)
			(effects
				(font
					(size 1.27 1.27)
				)
				(justify mirror)
			)
		)
		(property "Value" ""
			(at 0 0 90)
			(layer "B.Fab")
			(effects
				(font
					(size 1.27 1.27)
				)
				(justify mirror)
			)
		)
		(duplicate_pad_numbers_are_jumpers no)
		(fp_line
			(start -1.524 0.762)
			(end 1.524 0.762)
			(stroke
				(width 0.1524)
				(type default)
			)
			(layer "B.SilkS")
		)
		(fp_line
			(start 1.524 0.762)
			(end 1.524 -0.762)
			(stroke
				(width 0.1524)
				(type default)
			)
			(layer "B.SilkS")
		)
		(fp_line
			(start -1.524 -0.762)
			(end -1.524 0.762)
			(stroke
				(width 0.1524)
				(type default)
			)
			(layer "B.SilkS")
		)
		(fp_line
			(start 1.524 -0.762)
			(end -1.524 -0.762)
			(stroke
				(width 0.1524)
				(type default)
			)
			(layer "B.SilkS")
		)
		(fp_line
			(start -1.1049 0.724916)
			(end -1.1049 -0.724916)
			(stroke
				(width 0.1)
				(type default)
			)
			(layer "B.Fab")
		)
		(fp_line
			(start 1.1049 0.724916)
			(end -1.1049 0.724916)
			(stroke
				(width 0.1)
				(type default)
			)
			(layer "B.Fab")
		)
		(fp_line
			(start -1.1049 -0.724916)
			(end 1.1049 -0.724916)
			(stroke
				(width 0.1)
				(type default)
			)
			(layer "B.Fab")
		)
		(fp_line
			(start 1.1049 -0.724916)
			(end 1.1049 0.724916)
			(stroke
				(width 0.1)
				(type default)
			)
			(layer "B.Fab")
		)
		(pad "1" smd rect
			(at 0.889 0 270)
			(size 1.016 1.27)
			(layers "B.Cu" "B.Mask" "B.Paste")
			(net "P12V_S3_AUX_CPU1_NVDIMM")
		)
		(pad "2" smd rect
			(at -0.889 0 270)
			(size 1.016 1.27)
			(layers "B.Cu" "B.Mask" "B.Paste")
			(net "GND")
		)
	)
	(footprint ""
		(layer "B.Cu")
		(at 203.991464 -316.386718 90)
		(property "Reference" "R3906"
			(at 0 0 90)
			(layer "B.SilkS")
			(hide yes)
			(effects
				(font
					(size 1.27 1.27)
				)
				(justify mirror)
			)
		)
		(property "Value" ""
			(at 0 0 90)
			(layer "B.Fab")
			(effects
				(font
					(size 1.27 1.27)
				)
				(justify mirror)
			)
		)
		(duplicate_pad_numbers_are_jumpers no)
		(fp_line
			(start 0.7874 -0.4064)
			(end -0.7874 -0.4064)
			(stroke
				(width 0.1524)
				(type default)
			)
			(layer "B.SilkS")
		)
		(fp_line
			(start -0.7874 -0.4064)
			(end -0.7874 0.4064)
			(stroke
				(width 0.1524)
				(type default)
			)
			(layer "B.SilkS")
		)
		(fp_line
			(start 0.7874 0.4064)
			(end 0.7874 -0.4064)
			(stroke
				(width 0.1524)
				(type default)
			)
			(layer "B.SilkS")
		)
		(fp_line
			(start -0.7874 0.4064)
			(end 0.7874 0.4064)
			(stroke
				(width 0.1524)
				(type default)
			)
			(layer "B.SilkS")
		)
		(fp_line
			(start 0.67945 -0.305054)
			(end 0.12065 -0.305054)
			(stroke
				(width 0.1)
				(type default)
			)
			(layer "B.Fab")
		)
		(fp_line
			(start 0.12065 -0.305054)
			(end 0.12065 -0.2794)
			(stroke
				(width 0.1)
				(type default)
			)
			(layer "B.Fab")
		)
		(fp_line
			(start -0.12065 -0.3048)
			(end -0.67945 -0.3048)
			(stroke
				(width 0.1)
				(type default)
			)
			(layer "B.Fab")
		)
		(fp_line
			(start -0.67945 -0.3048)
			(end -0.67945 0.3048)
			(stroke
				(width 0.1)
				(type default)
			)
			(layer "B.Fab")
		)
		(fp_line
			(start 0.12065 -0.2794)
			(end -0.12065 -0.2794)
			(stroke
				(width 0.1)
				(type default)
			)
			(layer "B.Fab")
		)
		(fp_line
			(start -0.12065 -0.2794)
			(end -0.12065 -0.3048)
			(stroke
				(width 0.1)
				(type default)
			)
			(layer "B.Fab")
		)
		(fp_line
			(start 0.12065 0.2794)
			(end 0.12065 0.3048)
			(stroke
				(width 0.1)
				(type default)
			)
			(layer "B.Fab")
		)
		(fp_line
			(start -0.120396 0.2794)
			(end 0.12065 0.2794)
			(stroke
				(width 0.1)
				(type default)
			)
			(layer "B.Fab")
		)
		(fp_line
			(start 0.67945 0.3048)
			(end 0.67945 -0.305054)
			(stroke
				(width 0.1)
				(type default)
			)
			(layer "B.Fab")
		)
		(fp_line
			(start 0.12065 0.3048)
			(end 0.67945 0.3048)
			(stroke
				(width 0.1)
				(type default)
			)
			(layer "B.Fab")
		)
		(fp_line
			(start -0.120396 0.3048)
			(end -0.120396 0.2794)
			(stroke
				(width 0.1)
				(type default)
			)
			(layer "B.Fab")
		)
		(fp_line
			(start -0.67945 0.3048)
			(end -0.120396 0.3048)
			(stroke
				(width 0.1)
				(type default)
			)
			(layer "B.Fab")
		)
		(pad "1" smd circle
			(at 0.40005 0 270)
			(size 0 0)
			(layers "B.Cu" "B.Mask" "B.Paste")
			(net "I3C_SPD_DDREFGH_CPU1_LVC1_SCL_7")
		)
		(pad "2" smd circle
			(at -0.40005 0 270)
			(size 0 0)
			(layers "B.Cu" "B.Mask" "B.Paste")
			(net "I3C_SPD_DDREFGH_CPU1_LVC1_SCL")
		)
	)
	(footprint ""
		(layer "B.Cu")
		(at 421.853614 -319.263776 180)
		(property "Reference" "C35"
			(at 0 0 0)
			(layer "B.SilkS")
			(hide yes)
			(effects
				(font
					(size 1.27 1.27)
				)
				(justify mirror)
			)
		)
		(property "Value" ""
			(at 0 0 0)
			(layer "B.Fab")
			(effects
				(font
					(size 1.27 1.27)
				)
				(justify mirror)
			)
		)
		(duplicate_pad_numbers_are_jumpers no)
		(fp_line
			(start 0.7874 0.4064)
			(end 0.7874 -0.4064)
			(stroke
				(width 0.1524)
				(type default)
			)
			(layer "B.SilkS")
		)
		(fp_line
			(start 0.7874 -0.4064)
			(end -0.7874 -0.4064)
			(stroke
				(width 0.1524)
				(type default)
			)
			(layer "B.SilkS")
		)
		(fp_line
			(start -0.7874 0.4064)
			(end 0.7874 0.4064)
			(stroke
				(width 0.1524)
				(type default)
			)
			(layer "B.SilkS")
		)
		(fp_line
			(start -0.7874 -0.4064)
			(end -0.7874 0.4064)
			(stroke
				(width 0.1524)
				(type default)
			)
			(layer "B.SilkS")
		)
		(fp_line
			(start 0.67945 0.3048)
			(end 0.67945 -0.305054)
			(stroke
				(width 0.1)
				(type default)
			)
			(layer "B.Fab")
		)
		(fp_line
			(start 0.67945 -0.305054)
			(end 0.12065 -0.305054)
			(stroke
				(width 0.1)
				(type default)
			)
			(layer "B.Fab")
		)
		(fp_line
			(start 0.12065 0.3048)
			(end 0.67945 0.3048)
			(stroke
				(width 0.1)
				(type default)
			)
			(layer "B.Fab")
		)
		(fp_line
			(start 0.12065 0.2794)
			(end 0.12065 0.3048)
			(stroke
				(width 0.1)
				(type default)
			)
			(layer "B.Fab")
		)
		(fp_line
			(start 0.12065 -0.2794)
			(end -0.12065 -0.2794)
			(stroke
				(width 0.1)
				(type default)
			)
			(layer "B.Fab")
		)
		(fp_line
			(start 0.12065 -0.305054)
			(end 0.12065 -0.2794)
			(stroke
				(width 0.1)
				(type default)
			)
			(layer "B.Fab")
		)
		(fp_line
			(start -0.120396 0.3048)
			(end -0.120396 0.2794)
			(stroke
				(width 0.1)
				(type default)
			)
			(layer "B.Fab")
		)
		(fp_line
			(start -0.120396 0.2794)
			(end 0.12065 0.2794)
			(stroke
				(width 0.1)
				(type default)
			)
			(layer "B.Fab")
		)
		(fp_line
			(start -0.12065 -0.2794)
			(end -0.12065 -0.3048)
			(stroke
				(width 0.1)
				(type default)
			)
			(layer "B.Fab")
		)
		(fp_line
			(start -0.12065 -0.3048)
			(end -0.67945 -0.3048)
			(stroke
				(width 0.1)
				(type default)
			)
			(layer "B.Fab")
		)
		(fp_line
			(start -0.67945 0.3048)
			(end -0.120396 0.3048)
			(stroke
				(width 0.1)
				(type default)
			)
			(layer "B.Fab")
		)
		(fp_line
			(start -0.67945 -0.3048)
			(end -0.67945 0.3048)
			(stroke
				(width 0.1)
				(type default)
			)
			(layer "B.Fab")
		)
		(pad "1" smd circle
			(at 0.40005 0)
			(size 0 0)
			(layers "B.Cu" "B.Mask" "B.Paste")
			(net "P3V3_AUX")
		)
		(pad "2" smd circle
			(at -0.40005 0)
			(size 0 0)
			(layers "B.Cu" "B.Mask" "B.Paste")
			(net "GND")
		)
	)
	(footprint ""
		(layer "B.Cu")
		(at 325.168768 -345.774264 -90)
		(property "Reference" "PR137"
			(at 0 0 90)
			(layer "B.SilkS")
			(hide yes)
			(effects
				(font
					(size 1.27 1.27)
				)
				(justify mirror)
			)
		)
		(property "Value" ""
			(at 0 0 90)
			(layer "B.Fab")
			(effects
				(font
					(size 1.27 1.27)
				)
				(justify mirror)
			)
		)
		(duplicate_pad_numbers_are_jumpers no)
		(fp_line
			(start -0.7874 0.4064)
			(end 0.7874 0.4064)
			(stroke
				(width 0.1524)
				(type default)
			)
			(layer "B.SilkS")
		)
		(fp_line
			(start 0.7874 0.4064)
			(end 0.7874 -0.4064)
			(stroke
				(width 0.1524)
				(type default)
			)
			(layer "B.SilkS")
		)
		(fp_line
			(start -0.7874 -0.4064)
			(end -0.7874 0.4064)
			(stroke
				(width 0.1524)
				(type default)
			)
			(layer "B.SilkS")
		)
		(fp_line
			(start 0.7874 -0.4064)
			(end -0.7874 -0.4064)
			(stroke
				(width 0.1524)
				(type default)
			)
			(layer "B.SilkS")
		)
		(fp_line
			(start -0.67945 0.3048)
			(end -0.120396 0.3048)
			(stroke
				(width 0.1)
				(type default)
			)
			(layer "B.Fab")
		)
		(fp_line
			(start -0.120396 0.3048)
			(end -0.120396 0.2794)
			(stroke
				(width 0.1)
				(type default)
			)
			(layer "B.Fab")
		)
		(fp_line
			(start 0.12065 0.3048)
			(end 0.67945 0.3048)
			(stroke
				(width 0.1)
				(type default)
			)
			(layer "B.Fab")
		)
		(fp_line
			(start 0.67945 0.3048)
			(end 0.67945 -0.305054)
			(stroke
				(width 0.1)
				(type default)
			)
			(layer "B.Fab")
		)
		(fp_line
			(start -0.120396 0.2794)
			(end 0.12065 0.2794)
			(stroke
				(width 0.1)
				(type default)
			)
			(layer "B.Fab")
		)
		(fp_line
			(start 0.12065 0.2794)
			(end 0.12065 0.3048)
			(stroke
				(width 0.1)
				(type default)
			)
			(layer "B.Fab")
		)
		(fp_line
			(start -0.12065 -0.2794)
			(end -0.12065 -0.3048)
			(stroke
				(width 0.1)
				(type default)
			)
			(layer "B.Fab")
		)
		(fp_line
			(start 0.12065 -0.2794)
			(end -0.12065 -0.2794)
			(stroke
				(width 0.1)
				(type default)
			)
			(layer "B.Fab")
		)
		(fp_line
			(start -0.67945 -0.3048)
			(end -0.67945 0.3048)
			(stroke
				(width 0.1)
				(type default)
			)
			(layer "B.Fab")
		)
		(fp_line
			(start -0.12065 -0.3048)
			(end -0.67945 -0.3048)
			(stroke
				(width 0.1)
				(type default)
			)
			(layer "B.Fab")
		)
		(fp_line
			(start 0.12065 -0.305054)
			(end 0.12065 -0.2794)
			(stroke
				(width 0.1)
				(type default)
			)
			(layer "B.Fab")
		)
		(fp_line
			(start 0.67945 -0.305054)
			(end 0.12065 -0.305054)
			(stroke
				(width 0.1)
				(type default)
			)
			(layer "B.Fab")
		)
		(pad "1" smd circle
			(at 0.40005 0 90)
			(size 0 0)
			(layers "B.Cu" "B.Mask" "B.Paste")
			(net "PVCCIN_CPU0_VOS7")
		)
		(pad "2" smd circle
			(at -0.40005 0 90)
			(size 0 0)
			(layers "B.Cu" "B.Mask" "B.Paste")
			(net "PVCCIN_CPU0")
		)
	)
)
